(kicad_pcb
	(version 20260206)
	(generator "pcbnew")
	(generator_version "10.0")
	(general
		(thickness 1.6)
		(legacy_teardrops no)
	)
	(paper "A4")
	(title_block
		(title "Bryce Canyon_R.DPB_16317-1_OCP.brd")
		(comment 1 "Bryce Canyon / footprints 440-447 of 2099")
	)
	(layers
		(0 "F.Cu" signal "TOP")
		(4 "In1.Cu" signal "L2GND")
		(6 "In2.Cu" signal "L3")
		(8 "In3.Cu" signal "L4VCC")
		(10 "In4.Cu" signal "L5VCC")
		(12 "In5.Cu" signal "L6")
		(14 "In6.Cu" signal "L7GND")
		(2 "B.Cu" signal "BOTTOM")
		(9 "F.Adhes" user "F.Adhesive")
		(11 "B.Adhes" user "B.Adhesive")
		(13 "F.Paste" user "Package Geometry/Pastemask Top")
		(15 "B.Paste" user "Package Geometry/Pastemask Bottom")
		(5 "F.SilkS" user "Ref Des/Silkscreen Top")
		(7 "B.SilkS" user "Ref Des/Silkscreen Bottom")
		(1 "F.Mask" user "Board Geometry/Soldermask Top")
		(3 "B.Mask" user "Board Geometry/Soldermask Bottom")
		(17 "Dwgs.User" user "User.Drawings")
		(19 "Cmts.User" user "User.Comments")
		(21 "Eco1.User" user "User.Eco1")
		(23 "Eco2.User" user "User.Eco2")
		(25 "Edge.Cuts" user "Board Geometry/Outline")
		(27 "Margin" user)
		(31 "F.CrtYd" user "Package Geometry/Place Bound Top")
		(29 "B.CrtYd" user "Package Geometry/Place Bound Bottom")
		(35 "F.Fab" user "Ref Des/Assembly Top")
		(33 "B.Fab" user "Ref Des/Assembly Bottom")
	)
	(footprint ""
		(layer "F.Cu")
		(at 29.530802 -231.52735)
		(property "Reference" "TP202"
			(at 0 0 0)
			(layer "F.SilkS")
			(hide yes)
			(effects
				(font
					(size 1.27 1.27)
				)
			)
		)
		(property "Value" "*"
			(at -0.0508 -1.6764 0)
			(unlocked yes)
			(layer "F.Fab")
			(hide yes)
			(effects
				(font
					(size 1.016 1.016)
					(thickness 0.1524)
				)
			)
		)
		(property "Device Type" "TPAD32"
			(at -0.0508 -3.2004 0)
			(unlocked yes)
			(layer "F.Fab")
			(hide yes)
			(effects
				(font
					(size 1.016 1.016)
					(thickness 0.1524)
				)
			)
		)
		(duplicate_pad_numbers_are_jumpers no)
		(fp_poly
			(pts
				(arc
					(start 0.4064 0)
					(mid -0.4064 0)
					(end 0.4064 0)
				)
			)
			(stroke
				(width 0)
				(type default)
			)
			(fill no)
			(layer "F.CrtYd")
		)
		(fp_poly
			(pts
				(arc
					(start 0.7112 0)
					(mid -0.7112 0)
					(end 0.7112 0)
				)
			)
			(stroke
				(width 0)
				(type default)
			)
			(fill no)
			(layer "F.Fab")
		)
		(pad "1" smd circle
			(at 0 0)
			(size 0.8128 0.8128)
			(layers "F.Cu" "F.Mask" "F.Paste")
			(net "P5V_B_1_PGOOD")
		)
	)
	(footprint ""
		(layer "F.Cu")
		(at 434.880004 -360.2355 180)
		(property "Reference" "C404"
			(at 0 0 180)
			(layer "F.SilkS")
			(hide yes)
			(effects
				(font
					(size 1.27 1.27)
				)
			)
		)
		(property "Value" "SCD033U25V2KX-GP"
			(at 1.1811 -2.7051 180)
			(unlocked yes)
			(layer "F.Fab")
			(hide yes)
			(effects
				(font
					(size 1.016 1.016)
					(thickness 0.1524)
				)
			)
		)
		(property "Device Type" "C402H22"
			(at 1.1811 -4.2291 180)
			(unlocked yes)
			(layer "F.Fab")
			(hide yes)
			(effects
				(font
					(size 1.016 1.016)
					(thickness 0.1524)
				)
			)
		)
		(duplicate_pad_numbers_are_jumpers no)
		(fp_rect
			(start -0.4318 0.9525)
			(end 0.4318 -0.9525)
			(stroke
				(width 0)
				(type default)
			)
			(fill no)
			(layer "F.CrtYd")
		)
		(fp_rect
			(start -0.4318 0.9525)
			(end 0.4318 -0.9525)
			(stroke
				(width 0)
				(type default)
			)
			(fill no)
			(layer "F.Fab")
		)
		(pad "1" smd custom
			(at 0 -0.4445 180)
			(size 0.1524 0.1524)
			(layers "F.Cu" "F.Mask" "F.Paste")
			(net "GATE_FAN3_R")
			(options
				(clearance outline)
				(anchor circle)
			)
			(primitives
				(gr_poly
					(pts
						(arc
							(start 0.3048 -0.2032)
							(mid 0.275042 -0.275042)
							(end 0.2032 -0.3048)
						)
						(arc
							(start -0.2032 -0.3048)
							(mid -0.275042 -0.275042)
							(end -0.3048 -0.2032)
						)
						(arc
							(start -0.3048 0.2032)
							(mid -0.275042 0.275042)
							(end -0.2032 0.3048)
						)
						(arc
							(start 0.2032 0.3048)
							(mid 0.275042 0.275042)
							(end 0.3048 0.2032)
						)
					)
					(width 0)
					(fill yes)
				)
			)
		)
		(pad "2" smd custom
			(at 0 0.4445 180)
			(size 0.1524 0.1524)
			(layers "F.Cu" "F.Mask" "F.Paste")
			(net "P12V_IN")
			(options
				(clearance outline)
				(anchor circle)
			)
			(primitives
				(gr_poly
					(pts
						(arc
							(start 0.3048 -0.2032)
							(mid 0.275042 -0.275042)
							(end 0.2032 -0.3048)
						)
						(arc
							(start -0.2032 -0.3048)
							(mid -0.275042 -0.275042)
							(end -0.3048 -0.2032)
						)
						(arc
							(start -0.3048 0.2032)
							(mid -0.275042 0.275042)
							(end -0.2032 0.3048)
						)
						(arc
							(start 0.2032 0.3048)
							(mid 0.275042 0.275042)
							(end 0.3048 0.2032)
						)
					)
					(width 0)
					(fill yes)
				)
			)
		)
	)
	(footprint ""
		(layer "F.Cu")
		(at 286.032448 -347.541342)
		(property "Reference" "R1078"
			(at 0 0 0)
			(layer "F.SilkS")
			(hide yes)
			(effects
				(font
					(size 1.27 1.27)
				)
			)
		)
		(property "Value" "0R2J-2-GP"
			(at 0.064008 -3.993896 0)
			(unlocked yes)
			(layer "F.Fab")
			(hide yes)
			(effects
				(font
					(size 1.016 1.016)
					(thickness 0.1524)
				)
			)
		)
		(property "Device Type" "R402H16"
			(at 0.064008 -5.517896 0)
			(unlocked yes)
			(layer "F.Fab")
			(hide yes)
			(effects
				(font
					(size 1.016 1.016)
					(thickness 0.1524)
				)
			)
		)
		(duplicate_pad_numbers_are_jumpers no)
		(fp_line
			(start -0.508 -0.9398)
			(end -0.508 0.9398)
			(stroke
				(width 0.1524)
				(type default)
			)
			(layer "F.SilkS")
		)
		(fp_line
			(start 0.508 -0.9398)
			(end -0.508 -0.9398)
			(stroke
				(width 0.1524)
				(type default)
			)
			(layer "F.SilkS")
		)
		(fp_rect
			(start -0.508 0.9398)
			(end 0.508 -0.9398)
			(stroke
				(width 0)
				(type default)
			)
			(fill no)
			(layer "F.CrtYd")
		)
		(fp_rect
			(start -0.508 0.9398)
			(end 0.508 -0.9398)
			(stroke
				(width 0)
				(type default)
			)
			(fill no)
			(layer "F.Fab")
		)
		(pad "1" smd custom
			(at 0 -0.4445)
			(size 0.1397 0.1397)
			(layers "F.Cu" "F.Mask" "F.Paste")
			(net "MAX31790_B_ADD1")
			(options
				(clearance outline)
				(anchor circle)
			)
			(primitives
				(gr_poly
					(pts
						(arc
							(start -0.1778 -0.2794)
							(mid -0.249642 -0.249642)
							(end -0.2794 -0.1778)
						)
						(arc
							(start -0.2794 0.1778)
							(mid -0.249642 0.249642)
							(end -0.1778 0.2794)
						)
						(arc
							(start 0.1778 0.2794)
							(mid 0.249642 0.249642)
							(end 0.2794 0.1778)
						)
						(arc
							(start 0.2794 -0.1778)
							(mid 0.249642 -0.249642)
							(end 0.1778 -0.2794)
						)
					)
					(width 0)
					(fill yes)
				)
			)
		)
		(pad "2" smd custom
			(at 0 0.4445)
			(size 0.1397 0.1397)
			(layers "F.Cu" "F.Mask" "F.Paste")
			(net "GND")
			(options
				(clearance outline)
				(anchor circle)
			)
			(primitives
				(gr_poly
					(pts
						(arc
							(start -0.1778 -0.2794)
							(mid -0.249642 -0.249642)
							(end -0.2794 -0.1778)
						)
						(arc
							(start -0.2794 0.1778)
							(mid -0.249642 0.249642)
							(end -0.1778 0.2794)
						)
						(arc
							(start 0.1778 0.2794)
							(mid 0.249642 0.249642)
							(end 0.2794 0.1778)
						)
						(arc
							(start 0.2794 -0.1778)
							(mid 0.249642 -0.249642)
							(end 0.1778 -0.2794)
						)
					)
					(width 0)
					(fill yes)
				)
			)
		)
	)
	(footprint ""
		(layer "F.Cu")
		(at 174.117 -214.249)
		(property "Reference" "R285"
			(at 0 0 0)
			(layer "F.SilkS")
			(hide yes)
			(effects
				(font
					(size 1.27 1.27)
				)
			)
		)
		(property "Value" "91R3F-1-GP"
			(at -0.0254 -2.5146 0)
			(unlocked yes)
			(layer "F.Fab")
			(hide yes)
			(effects
				(font
					(size 1.016 1.016)
					(thickness 0.1524)
				)
			)
		)
		(property "Device Type" "R603H22"
			(at -0.0254 -4.0386 0)
			(unlocked yes)
			(layer "F.Fab")
			(hide yes)
			(effects
				(font
					(size 1.016 1.016)
					(thickness 0.1524)
				)
			)
		)
		(duplicate_pad_numbers_are_jumpers no)
		(fp_line
			(start -0.4826 0)
			(end -0.2032 0)
			(stroke
				(width 0.2032)
				(type default)
			)
			(layer "F.SilkS")
		)
		(fp_line
			(start 0.2032 0)
			(end 0.4826 0)
			(stroke
				(width 0.2032)
				(type default)
			)
			(layer "F.SilkS")
		)
		(fp_rect
			(start -0.5842 1.3335)
			(end 0.5842 -1.3335)
			(stroke
				(width 0)
				(type default)
			)
			(fill no)
			(layer "F.CrtYd")
		)
		(fp_rect
			(start -0.5842 1.3335)
			(end 0.5842 -1.3335)
			(stroke
				(width 0)
				(type default)
			)
			(fill no)
			(layer "F.Fab")
		)
		(pad "1" smd custom
			(at 0 -0.762)
			(size 0.2159 0.2159)
			(layers "F.Cu" "F.Mask" "F.Paste")
			(net "P5V_B_1")
			(options
				(clearance outline)
				(anchor circle)
			)
			(primitives
				(gr_poly
					(pts
						(arc
							(start -0.3302 -0.4318)
							(mid -0.402042 -0.402042)
							(end -0.4318 -0.3302)
						)
						(arc
							(start -0.4318 0.3302)
							(mid -0.402042 0.402042)
							(end -0.3302 0.4318)
						)
						(arc
							(start 0.3302 0.4318)
							(mid 0.402042 0.402042)
							(end 0.4318 0.3302)
						)
						(arc
							(start 0.4318 -0.3302)
							(mid 0.402042 -0.402042)
							(end 0.3302 -0.4318)
						)
					)
					(width 0)
					(fill yes)
				)
			)
		)
		(pad "2" smd custom
			(at 0 0.762)
			(size 0.2159 0.2159)
			(layers "F.Cu" "F.Mask" "F.Paste")
			(net "DRV_ACT_5")
			(options
				(clearance outline)
				(anchor circle)
			)
			(primitives
				(gr_poly
					(pts
						(arc
							(start -0.3302 -0.4318)
							(mid -0.402042 -0.402042)
							(end -0.4318 -0.3302)
						)
						(arc
							(start -0.4318 0.3302)
							(mid -0.402042 0.402042)
							(end -0.3302 0.4318)
						)
						(arc
							(start 0.3302 0.4318)
							(mid 0.402042 0.402042)
							(end 0.4318 0.3302)
						)
						(arc
							(start 0.4318 -0.3302)
							(mid 0.402042 -0.402042)
							(end 0.3302 -0.4318)
						)
					)
					(width 0)
					(fill yes)
				)
			)
		)
	)
	(footprint ""
		(layer "F.Cu")
		(at 54.737 -19.177)
		(property "Reference" "R653"
			(at 0 0 0)
			(layer "F.SilkS")
			(hide yes)
			(effects
				(font
					(size 1.27 1.27)
				)
			)
		)
		(property "Value" "1KR2F-3-GP"
			(at 0.064008 -3.993896 0)
			(unlocked yes)
			(layer "F.Fab")
			(hide yes)
			(effects
				(font
					(size 1.016 1.016)
					(thickness 0.1524)
				)
			)
		)
		(property "Device Type" "R402H16"
			(at 0.064008 -5.517896 0)
			(unlocked yes)
			(layer "F.Fab")
			(hide yes)
			(effects
				(font
					(size 1.016 1.016)
					(thickness 0.1524)
				)
			)
		)
		(duplicate_pad_numbers_are_jumpers no)
		(fp_line
			(start -0.508 -0.9398)
			(end -0.508 0.9398)
			(stroke
				(width 0.1524)
				(type default)
			)
			(layer "F.SilkS")
		)
		(fp_line
			(start 0.508 -0.9398)
			(end -0.508 -0.9398)
			(stroke
				(width 0.1524)
				(type default)
			)
			(layer "F.SilkS")
		)
		(fp_rect
			(start -0.508 0.9398)
			(end 0.508 -0.9398)
			(stroke
				(width 0)
				(type default)
			)
			(fill no)
			(layer "F.CrtYd")
		)
		(fp_rect
			(start -0.508 0.9398)
			(end 0.508 -0.9398)
			(stroke
				(width 0)
				(type default)
			)
			(fill no)
			(layer "F.Fab")
		)
		(pad "1" smd custom
			(at 0 -0.4445)
			(size 0.1397 0.1397)
			(layers "F.Cu" "F.Mask" "F.Paste")
			(net "P3V3_STBY_B")
			(options
				(clearance outline)
				(anchor circle)
			)
			(primitives
				(gr_poly
					(pts
						(arc
							(start -0.1778 -0.2794)
							(mid -0.249642 -0.249642)
							(end -0.2794 -0.1778)
						)
						(arc
							(start -0.2794 0.1778)
							(mid -0.249642 0.249642)
							(end -0.1778 0.2794)
						)
						(arc
							(start 0.1778 0.2794)
							(mid 0.249642 0.249642)
							(end 0.2794 0.1778)
						)
						(arc
							(start 0.2794 -0.1778)
							(mid 0.249642 -0.249642)
							(end 0.1778 -0.2794)
						)
					)
					(width 0)
					(fill yes)
				)
			)
		)
		(pad "2" smd custom
			(at 0 0.4445)
			(size 0.1397 0.1397)
			(layers "F.Cu" "F.Mask" "F.Paste")
			(net "SW_PWR_R_HDD25")
			(options
				(clearance outline)
				(anchor circle)
			)
			(primitives
				(gr_poly
					(pts
						(arc
							(start -0.1778 -0.2794)
							(mid -0.249642 -0.249642)
							(end -0.2794 -0.1778)
						)
						(arc
							(start -0.2794 0.1778)
							(mid -0.249642 0.249642)
							(end -0.1778 0.2794)
						)
						(arc
							(start 0.1778 0.2794)
							(mid 0.249642 0.249642)
							(end 0.2794 0.1778)
						)
						(arc
							(start 0.2794 -0.1778)
							(mid 0.249642 -0.249642)
							(end 0.1778 -0.2794)
						)
					)
					(width 0)
					(fill yes)
				)
			)
		)
	)
	(footprint ""
		(layer "F.Cu")
		(at 14.5542 -214.757 180)
		(property "Reference" "Q219"
			(at 0 0 180)
			(layer "F.SilkS")
			(hide yes)
			(effects
				(font
					(size 1.27 1.27)
				)
			)
		)
		(property "Value" "2N7002K-2-GP"
			(at 0.127 -8.9662 180)
			(unlocked yes)
			(layer "F.Fab")
			(hide yes)
			(effects
				(font
					(size 1.016 1.016)
					(thickness 0.1524)
				)
			)
		)
		(property "Device Type" "SOT23DGS2D4H44"
			(at 0.127 -10.4902 180)
			(unlocked yes)
			(layer "F.Fab")
			(hide yes)
			(effects
				(font
					(size 1.016 1.016)
					(thickness 0.1524)
				)
			)
		)
		(duplicate_pad_numbers_are_jumpers no)
		(fp_line
			(start 1.651 1.778)
			(end 1.651 -1.778)
			(stroke
				(width 0.1524)
				(type default)
			)
			(layer "F.SilkS")
		)
		(fp_line
			(start 1.651 -1.778)
			(end -1.651 -1.778)
			(stroke
				(width 0.1524)
				(type default)
			)
			(layer "F.SilkS")
		)
		(fp_line
			(start -1.651 1.778)
			(end 1.651 1.778)
			(stroke
				(width 0.1524)
				(type default)
			)
			(layer "F.SilkS")
		)
		(fp_line
			(start -1.651 -1.778)
			(end -1.651 1.778)
			(stroke
				(width 0.1524)
				(type default)
			)
			(layer "F.SilkS")
		)
		(fp_poly
			(pts
				(xy -1.778 1.8796) (xy -1.778 -1.8796) (xy 1.778 -1.8796) (xy 1.778 1.8796)
			)
			(stroke
				(width 0)
				(type default)
			)
			(fill no)
			(layer "F.CrtYd")
		)
		(fp_poly
			(pts
				(xy -1.778 1.8796) (xy -1.778 -1.8796) (xy 1.778 -1.8796) (xy 1.778 1.8796)
			)
			(stroke
				(width 0)
				(type default)
			)
			(fill no)
			(layer "F.Fab")
		)
		(pad "D" smd custom
			(at 0 -0.9525 180)
			(size 0.1905 0.1905)
			(layers "F.Cu" "F.Mask" "F.Paste")
			(net "FLT_HDD0_N")
			(options
				(clearance outline)
				(anchor circle)
			)
			(primitives
				(gr_poly
					(pts
						(arc
							(start -0.1778 0.5715)
							(mid -0.321484 0.511984)
							(end -0.381 0.3683)
						)
						(arc
							(start -0.381 -0.3683)
							(mid -0.321484 -0.511984)
							(end -0.1778 -0.5715)
						)
						(arc
							(start 0.1778 -0.5715)
							(mid 0.321484 -0.511984)
							(end 0.381 -0.3683)
						)
						(arc
							(start 0.381 0.3683)
							(mid 0.321484 0.511984)
							(end 0.1778 0.5715)
						)
					)
					(width 0)
					(fill yes)
				)
			)
		)
		(pad "G" smd custom
			(at -0.98425 0.9525 180)
			(size 0.1905 0.1905)
			(layers "F.Cu" "F.Mask" "F.Paste")
			(net "DRIVE_B_0_FLT_LED")
			(options
				(clearance outline)
				(anchor circle)
			)
			(primitives
				(gr_poly
					(pts
						(arc
							(start -0.1778 0.5715)
							(mid -0.321484 0.511984)
							(end -0.381 0.3683)
						)
						(arc
							(start -0.381 -0.3683)
							(mid -0.321484 -0.511984)
							(end -0.1778 -0.5715)
						)
						(arc
							(start 0.1778 -0.5715)
							(mid 0.321484 -0.511984)
							(end 0.381 -0.3683)
						)
						(arc
							(start 0.381 0.3683)
							(mid 0.321484 0.511984)
							(end 0.1778 0.5715)
						)
					)
					(width 0)
					(fill yes)
				)
			)
		)
		(pad "S" smd custom
			(at 0.98425 0.9525 180)
			(size 0.1905 0.1905)
			(layers "F.Cu" "F.Mask" "F.Paste")
			(net "GND")
			(options
				(clearance outline)
				(anchor circle)
			)
			(primitives
				(gr_poly
					(pts
						(arc
							(start -0.1778 0.5715)
							(mid -0.321484 0.511984)
							(end -0.381 0.3683)
						)
						(arc
							(start -0.381 -0.3683)
							(mid -0.321484 -0.511984)
							(end -0.1778 -0.5715)
						)
						(arc
							(start 0.1778 -0.5715)
							(mid 0.321484 -0.511984)
							(end 0.381 -0.3683)
						)
						(arc
							(start 0.381 0.3683)
							(mid 0.321484 0.511984)
							(end 0.1778 0.5715)
						)
					)
					(width 0)
					(fill yes)
				)
			)
		)
	)
	(footprint ""
		(layer "F.Cu")
		(at 37.305996 -367.157 -90)
		(property "Reference" "D38"
			(at 0 0 270)
			(layer "F.SilkS")
			(hide yes)
			(effects
				(font
					(size 1.27 1.27)
				)
			)
		)
		(property "Value" "BAS16H-GP"
			(at 0 -5.5372 270)
			(unlocked yes)
			(layer "F.Fab")
			(hide yes)
			(effects
				(font
					(size 1.016 1.016)
					(thickness 0.1524)
				)
			)
		)
		(property "Device Type" "SOD123AKH48"
			(at 0 -7.0612 270)
			(unlocked yes)
			(layer "F.Fab")
			(hide yes)
			(effects
				(font
					(size 1.016 1.016)
					(thickness 0.1524)
				)
			)
		)
		(duplicate_pad_numbers_are_jumpers no)
		(fp_line
			(start 0.889 2.921)
			(end -0.889 2.921)
			(stroke
				(width 0.508)
				(type default)
			)
			(layer "F.SilkS")
		)
		(fp_line
			(start -1.016 2.667)
			(end 1.016 2.667)
			(stroke
				(width 0.1524)
				(type default)
			)
			(layer "F.SilkS")
		)
		(fp_line
			(start 1.016 2.667)
			(end 1.016 -2.667)
			(stroke
				(width 0.1524)
				(type default)
			)
			(layer "F.SilkS")
		)
		(fp_line
			(start -1.016 -2.667)
			(end -1.016 2.667)
			(stroke
				(width 0.1524)
				(type default)
			)
			(layer "F.SilkS")
		)
		(fp_line
			(start 1.016 -2.667)
			(end -1.016 -2.667)
			(stroke
				(width 0.1524)
				(type default)
			)
			(layer "F.SilkS")
		)
		(fp_rect
			(start -1.143 3.175)
			(end 1.143 -2.794)
			(stroke
				(width 0)
				(type default)
			)
			(fill no)
			(layer "F.CrtYd")
		)
		(fp_poly
			(pts
				(xy -1.143 -2.794) (xy 1.143 -2.794) (xy 1.143 3.175) (xy -1.143 3.175)
			)
			(stroke
				(width 0)
				(type default)
			)
			(fill no)
			(layer "F.Fab")
		)
		(pad "A" smd rect
			(at 0 -1.6891 270)
			(size 0.889 1.397)
			(layers "F.Cu" "F.Mask" "F.Paste")
			(net "FAN_0_TACH1")
		)
		(pad "K" smd rect
			(at 0 1.6891 270)
			(size 0.889 1.397)
			(layers "F.Cu" "F.Mask" "F.Paste")
			(net "P12V_IN")
		)
	)
	(footprint ""
		(layer "F.Cu")
		(at 143.002 -24.13 -90)
		(property "Reference" "C402"
			(at 0 0 270)
			(layer "F.SilkS")
			(hide yes)
			(effects
				(font
					(size 1.27 1.27)
				)
			)
		)
		(property "Value" "SCD033U25V2KX-GP"
			(at 1.1811 -2.7051 270)
			(unlocked yes)
			(layer "F.Fab")
			(hide yes)
			(effects
				(font
					(size 1.016 1.016)
					(thickness 0.1524)
				)
			)
		)
		(property "Device Type" "C402H22"
			(at 1.1811 -4.2291 270)
			(unlocked yes)
			(layer "F.Fab")
			(hide yes)
			(effects
				(font
					(size 1.016 1.016)
					(thickness 0.1524)
				)
			)
		)
		(duplicate_pad_numbers_are_jumpers no)
		(fp_rect
			(start -0.4318 0.9525)
			(end 0.4318 -0.9525)
			(stroke
				(width 0)
				(type default)
			)
			(fill no)
			(layer "F.CrtYd")
		)
		(fp_rect
			(start -0.4318 0.9525)
			(end 0.4318 -0.9525)
			(stroke
				(width 0)
				(type default)
			)
			(fill no)
			(layer "F.Fab")
		)
		(pad "1" smd custom
			(at 0 -0.4445 270)
			(size 0.1524 0.1524)
			(layers "F.Cu" "F.Mask" "F.Paste")
			(net "SW_HDD_P28")
			(options
				(clearance outline)
				(anchor circle)
			)
			(primitives
				(gr_poly
					(pts
						(arc
							(start 0.3048 -0.2032)
							(mid 0.275042 -0.275042)
							(end 0.2032 -0.3048)
						)
						(arc
							(start -0.2032 -0.3048)
							(mid -0.275042 -0.275042)
							(end -0.3048 -0.2032)
						)
						(arc
							(start -0.3048 0.2032)
							(mid -0.275042 0.275042)
							(end -0.2032 0.3048)
						)
						(arc
							(start 0.2032 0.3048)
							(mid 0.275042 0.275042)
							(end 0.3048 0.2032)
						)
					)
					(width 0)
					(fill yes)
				)
			)
		)
		(pad "2" smd custom
			(at 0 0.4445 270)
			(size 0.1524 0.1524)
			(layers "F.Cu" "F.Mask" "F.Paste")
			(net "GND")
			(options
				(clearance outline)
				(anchor circle)
			)
			(primitives
				(gr_poly
					(pts
						(arc
							(start 0.3048 -0.2032)
							(mid 0.275042 -0.275042)
							(end 0.2032 -0.3048)
						)
						(arc
							(start -0.2032 -0.3048)
							(mid -0.275042 -0.275042)
							(end -0.3048 -0.2032)
						)
						(arc
							(start -0.3048 0.2032)
							(mid -0.275042 0.275042)
							(end -0.2032 0.3048)
						)
						(arc
							(start 0.2032 0.3048)
							(mid 0.275042 0.275042)
							(end 0.3048 0.2032)
						)
					)
					(width 0)
					(fill yes)
				)
			)
		)
	)
)
